%FSTAX25Y25*%
%MOIN*%
%SFA1B1*%

%IPPOS*%
%ADD9500C,0.008000*%
%ADD9501C,0.021660*%
%ADD9502C,0.029920*%
%ADD9503C,0.030000*%
%ADD9504C,0.050000*%
%ADD9505C,0.060000*%
%ADD9506C,0.064960*%
%ADD9507C,0.068000*%
%ADD9508C,0.070870*%
%ADD9509C,0.118110*%
%ADD9510C,0.125000*%
%ADD9511C,0.035430*%
%ADD9512C,0.065980*%
%ADD9513C,0.118110*%
%LNgrandmaster-roundholes-1*%
%LPD*%
G54D9500*
X09633Y0564D03*
X09594Y05686D03*
X0888285Y0583251D03*
X08852Y05824D03*
X08822Y05792D03*
X08783Y0579D03*
X087657Y0582263D03*
X08734Y05827D03*
X08727Y05947D03*
X08694Y05952D03*
X08692Y05985D03*
X08658D03*
X08622Y05978D03*
X08588Y05979D03*
X08601Y05938D03*
X08505Y05941D03*
X08469D03*
X08405D03*
X08302Y05938D03*
X08303Y06097D03*
X08401Y06093D03*
X08499Y06094D03*
X08597Y06095D03*
X08656Y06096D03*
X08715Y06097D03*
X08774Y06098D03*
X08833Y06099D03*
X08892D03*
X0882941Y0599141D03*
X088Y05978D03*
X0876532Y0598081D03*
X0873525Y0599177D03*
X08924Y05957D03*
X08616Y05817D03*
X08582D03*
X08655Y05401D03*
X08695Y054D03*
X0881Y05399D03*
X08845D03*
X0897Y05398D03*
X0901Y054D03*
X08922Y05287D03*
X08898D03*
X0887205Y0525689D03*
X0894587Y0525591D03*
X090876Y0524705D03*
X0878937Y0525591D03*
X0876Y0529D03*
X08736D03*
X08595Y05288D03*
X08566Y05289D03*
X0853622Y0524878D03*
X0862703Y0525184D03*
X0843701Y0525D03*
X08422Y05285D03*
X08398D03*
X083Y0525D03*
X0814173Y0525984D03*
Y0529134D03*
X0810236D03*
Y0525984D03*
X0806693D03*
Y0529134D03*
X08025Y0525D03*
X079063Y052487D03*
X0786221Y0525984D03*
X0784252D03*
X0782283D03*
Y0529134D03*
X0784252D03*
X0786221D03*
X08345Y05434D03*
X08369D03*
X0846Y05402D03*
X08502Y05401D03*
X07788Y05359D03*
X07247Y05946D03*
X06995Y0591D03*
X06645Y05794D03*
X06646Y06032D03*
X06645Y06318D03*
X06644Y06555D03*
X06645Y06843D03*
Y07077D03*
Y07369D03*
X0664412Y0759783D03*
X07011Y07485D03*
X07252Y07486D03*
X07239Y07004D03*
X07Y0696D03*
X06999Y06434D03*
X07233Y06476D03*
X07662Y06501D03*
X07709D03*
X0771Y0654D03*
X07705Y06599D03*
X07661D03*
Y06698D03*
X07712D03*
X07709Y06796D03*
X07662D03*
X07666Y06895D03*
X07712Y06894D03*
Y06993D03*
X07665D03*
X0755836Y0707164D03*
X0761Y07125D03*
X07745Y0713D03*
X07707Y06403D03*
X07662D03*
X07556Y06323D03*
X07782Y06301D03*
X07995Y0634D03*
X08019Y063656D03*
X0805Y0639D03*
X08074Y064156D03*
X08197Y06302D03*
X08265Y0651D03*
X08437Y06441D03*
X08493Y0632D03*
X08685Y06485D03*
X0871Y06595D03*
X08634Y0662D03*
X08657Y06644D03*
X08595Y06738D03*
X08617Y06774D03*
X0857Y06794D03*
X0854Y06759D03*
X08375Y06945D03*
X084Y06971D03*
X0829Y0692D03*
X08321Y07219D03*
X08244Y07283D03*
X084Y07287D03*
Y07318D03*
X08441Y07286D03*
X08466Y07295D03*
X0849Y0724D03*
X0857Y07285D03*
X08572Y07312D03*
X08636Y07278D03*
X08656Y07295D03*
X08693Y07293D03*
X08717Y07297D03*
X08676Y07315D03*
X08794Y07311D03*
X08862Y07301D03*
X08832Y07267D03*
X08933Y0729D03*
X08976Y07291D03*
X08911Y07432D03*
X08885Y07435D03*
X08939Y0746D03*
X08949Y07625D03*
X08872Y0757D03*
X08812Y07605D03*
X08774Y07572D03*
X08676D03*
X08577Y07573D03*
X08615Y07465D03*
X0859Y0744D03*
X08566Y07416D03*
X08479Y07417D03*
X08466Y0746D03*
X08516Y07467D03*
X08395Y07416D03*
X084Y07583D03*
X0841935Y07625D03*
X08485Y07665D03*
Y077D03*
X08406Y07796D03*
X08314Y0759D03*
X082219Y075881D03*
X082425Y076175D03*
X0826219Y0746781D03*
X08137Y07757D03*
X07875Y07075D03*
X0787009Y0681574D03*
X07884Y06697D03*
X0781294Y0667794D03*
X0788746Y0652046D03*
X08885Y06565D03*
X0891Y0654D03*
X09215Y0666528D03*
X09243Y06665D03*
X0918742Y06718D03*
X09268Y06809D03*
X0931933Y0683D03*
X09289Y06975D03*
X09333Y07267D03*
X08774Y07433D03*
X0937Y0639D03*
Y0634D03*
X09395Y0636726D03*
X0939744Y0641526D03*
X09397Y06465D03*
X09404Y06577D03*
X09401Y0671759D03*
X0940462Y06809D03*
X09383Y06875D03*
X0942941Y0687488D03*
X09545Y06895D03*
Y06845D03*
Y06945D03*
Y06995D03*
X09562Y07037D03*
Y07062D03*
X0971Y07D03*
Y06925D03*
Y0677D03*
X09709Y06717D03*
X09715Y06679D03*
X0976402Y0667004D03*
X09794Y06695D03*
X09795Y06844D03*
X09935Y0682D03*
X10055Y068D03*
X10125Y06755D03*
X10122Y0669D03*
X10125Y06655D03*
X1014146Y0662756D03*
X1017Y06605D03*
X10025Y0655D03*
X09985Y06555D03*
X0996Y06556D03*
X09915Y0654D03*
X09885Y0657D03*
X09855Y06515D03*
X09825Y06485D03*
X09723Y06422D03*
X0954Y06417D03*
Y06445D03*
X09585Y06518D03*
X09581Y06666D03*
X0958Y06715D03*
X09987D03*
X09959Y06675D03*
X10055Y06515D03*
X1003Y0741D03*
X10055Y07726D03*
X09951Y07728D03*
X10225Y07729D03*
X1033D03*
X1049382Y0779382D03*
X09614Y07591D03*
X0957Y0759D03*
X09489Y07345D03*
X11568Y07218D03*
X11625Y0724D03*
X12039Y07175D03*
X11995Y07438D03*
X12265Y07395D03*
X12275Y07505D03*
X12388D03*
X12389Y07457D03*
X12387Y0756D03*
X12388Y07614D03*
X12389Y07661D03*
X12415Y07185D03*
X12386Y07115D03*
X12598Y0718D03*
X1269Y06885D03*
X12676Y06832D03*
X12592Y06781D03*
X12593Y06726D03*
Y06676D03*
Y06616D03*
X12539Y06535D03*
X12619Y06376D03*
X12835Y06665D03*
X13042Y06961D03*
X1294Y07099D03*
X12617Y08036D03*
X126378Y0813386D03*
X12639Y08345D03*
X125Y0846D03*
X1247Y0843D03*
X1243773Y084D03*
X124Y08375D03*
X1234491Y0833508D03*
X12325Y0827D03*
X1227257Y0823D03*
X1229957Y08203D03*
X1233Y08155D03*
X12295Y08125D03*
X1243Y08195D03*
X12467Y08235D03*
X12435Y08295D03*
X12447Y08013D03*
X123622Y0791339D03*
X1224409D03*
X12285Y08705D03*
X11985Y08556D03*
X11724Y0856D03*
X11667Y0855D03*
X11265Y08515D03*
X1125716Y0909284D03*
X10901Y09207D03*
X1074487Y0911987D03*
X10378Y0921D03*
X10185Y08888D03*
X10076Y08896D03*
X1003Y08788D03*
X1004Y08669D03*
X1012Y0852D03*
X10245Y0878D03*
X09821Y08766D03*
X0982Y0881D03*
X0969Y0884D03*
Y08755D03*
X0953Y0881D03*
X09522Y08664D03*
X09415Y0864D03*
X09427Y08461D03*
X0946Y0846D03*
X09385Y08451D03*
X0952Y08485D03*
X09613Y0849D03*
X09644Y08297D03*
X09735Y08265D03*
Y08346D03*
X09797Y08239D03*
X0979Y08205D03*
X0982Y0818D03*
X09845Y08155D03*
X09871Y08113D03*
X0993Y08125D03*
X10059Y08139D03*
X10105D03*
X10143D03*
X10199D03*
X10263D03*
X10324D03*
X10422D03*
X10468D03*
X1085Y08D03*
X1066Y0861D03*
X09768Y09027D03*
X09495Y0909D03*
X09386Y09226D03*
X09482Y08301D03*
X0953302Y0832298D03*
X09592Y08142D03*
X09482Y08107D03*
X0957Y07947D03*
X09592Y07896D03*
X09708Y08076D03*
X09359Y08054D03*
X09335Y08D03*
X09361Y07892D03*
X09188Y07974D03*
X0907Y07985D03*
X09023Y07972D03*
X09009Y07901D03*
X0909Y07916D03*
X08907Y07907D03*
X08875Y07903D03*
X08807Y07907D03*
X08753Y07906D03*
X08714Y07924D03*
X08622Y0788D03*
X08464Y07984D03*
X08495Y08086D03*
X08414Y08127D03*
X0841Y08198D03*
X08404Y08299D03*
X0832Y08365D03*
X0825Y08265D03*
X08196Y08204D03*
X08225Y0851D03*
X08245Y0854D03*
X0838Y08485D03*
X08425Y0855D03*
X0857Y0849D03*
X08665Y08505D03*
X08715Y08525D03*
X08765Y0857D03*
X0879Y0862D03*
X0867Y08665D03*
X08715Y08733D03*
X0871257Y0879001D03*
X08851Y08791D03*
X0898354Y08755D03*
X09005Y08835D03*
X0921Y0881D03*
X0926Y08792D03*
X09265Y0861D03*
X0923Y086D03*
X09349Y08452D03*
X09293Y08348D03*
X09321Y08305D03*
X09365Y08277D03*
X09243Y08297D03*
X09221Y08239D03*
X09188Y08218D03*
X0903536Y0821364D03*
X09048Y08159D03*
X0891732Y0814961D03*
X0888976D03*
X0885827D03*
X0883071D03*
Y0811811D03*
X0885827D03*
X0888976D03*
X0891732D03*
Y081811D03*
X0888976D03*
Y082126D03*
X0891732D03*
X0885827D03*
X0883071D03*
Y081811D03*
X0885827D03*
X08716Y08164D03*
X08717Y08329D03*
X08625Y0841D03*
X08581Y08292D03*
X08582Y08204D03*
X08887Y08382D03*
X08961Y08415D03*
X08975Y0805D03*
X08879Y09225D03*
X08561Y09287D03*
X08281Y09221D03*
X08235Y09021D03*
X08075Y089D03*
X0805Y08875D03*
X0802Y0884D03*
X07995Y0882D03*
X0813Y08742D03*
X08249Y08745D03*
X0813Y08615D03*
X07875Y08605D03*
X0784Y08705D03*
X07894Y09022D03*
X0774Y09114D03*
X0777Y0916D03*
X07682Y09083D03*
X07576Y09129D03*
X07548Y09233D03*
X07717Y0933D03*
X07779Y09331D03*
X07285Y0926D03*
X07431Y08561D03*
X0754Y08625D03*
X07565Y086D03*
X07745Y08665D03*
X0745Y08151D03*
G54D9501*
X081933Y0596253D03*
X089807D03*
X0768699Y0631377D03*
Y0710117D03*
X0819329Y0744247D03*
X0898069D03*
X095619Y0710113D03*
Y0631373D03*
G54D9502*
X084125Y0808615D03*
Y0824363D03*
X084075Y0844937D03*
Y0860685D03*
G54D9503*
X0803Y09056D03*
Y09156D03*
Y09256D03*
X07429Y09264D03*
Y09164D03*
Y09064D03*
G54D9504*
X1156831Y0589456D03*
X0996988D03*
Y0749298D03*
X1005256Y0759928D03*
X1017067D03*
X1028878D03*
X1156831Y0749298D03*
Y0669377D03*
G54D9505*
X0619Y0591D03*
Y06435D03*
Y0696D03*
Y07485D03*
G54D9506*
X117122Y0896D03*
Y091411D03*
G54D9507*
X0629Y0581D03*
Y0601D03*
X0609D03*
Y0581D03*
Y06335D03*
Y06535D03*
Y0686D03*
Y0706D03*
Y07385D03*
Y07585D03*
X0629D03*
Y07385D03*
Y0706D03*
Y0686D03*
Y06535D03*
Y06335D03*
G54D9508*
X1255965Y0859346D03*
X12725D03*
X1289035D03*
Y0881D03*
X12725D03*
X1255965D03*
G54D9509*
X096081Y0592023D03*
X076431D03*
X076421Y0749023D03*
X096081D03*
G54D9510*
X13206Y05701D03*
X06285Y05373D03*
X13206Y09168D03*
X06294Y09156D03*
G54D9511*
X09775Y0913D03*
X0994823D03*
G54D9512*
X08985Y0909004D03*
X09285D03*
G54D9513*
X1255965Y090974D03*
X1289035D03*
M02*